(kicad_pcb
	(version 20260206)
	(generator "pcbnew")
	(generator_version "10.0")
	(general
		(thickness 1.6)
		(legacy_teardrops no)
	)
	(paper "A4")
	(title_block
		(title "01162023_DA0F0TEBIF0_F0T_Expander_BD_F_brd_V02_OCP.brd")
		(comment 1 "Grand Teton / footprints 116-123 of 9728")
	)
	(layers
		(0 "F.Cu" signal "TOP")
		(4 "In1.Cu" signal "GND")
		(6 "In2.Cu" signal "VCC")
		(8 "In3.Cu" signal "VCC1")
		(10 "In4.Cu" signal "GND1")
		(12 "In5.Cu" signal "IN1")
		(14 "In6.Cu" signal "GND2")
		(16 "In7.Cu" signal "IN2")
		(18 "In8.Cu" signal "GND3")
		(20 "In9.Cu" signal "IN3")
		(22 "In10.Cu" signal "GND4")
		(24 "In11.Cu" signal "IN4")
		(26 "In12.Cu" signal "GND5")
		(28 "In13.Cu" signal "IN5")
		(30 "In14.Cu" signal "GND6")
		(32 "In15.Cu" signal "IN6")
		(34 "In16.Cu" signal "GND7")
		(2 "B.Cu" signal "BOTTOM")
		(9 "F.Adhes" user "F.Adhesive")
		(11 "B.Adhes" user "B.Adhesive")
		(13 "F.Paste" user "Package Geometry/Pastemask Top")
		(15 "B.Paste" user "Package Geometry/Pastemask Bottom")
		(5 "F.SilkS" user "Ref Des/Silkscreen Top")
		(7 "B.SilkS" user "Ref Des/Silkscreen Bottom")
		(1 "F.Mask" user "Board Geometry/Soldermask Top")
		(3 "B.Mask" user "Board Geometry/Soldermask Bottom")
		(17 "Dwgs.User" user "User.Drawings")
		(19 "Cmts.User" user "User.Comments")
		(21 "Eco1.User" user "User.Eco1")
		(23 "Eco2.User" user "User.Eco2")
		(25 "Edge.Cuts" user "Board Geometry/Outline")
		(27 "Margin" user)
		(31 "F.CrtYd" user "Package Geometry/Place Bound Top")
		(29 "B.CrtYd" user "Package Geometry/Place Bound Bottom")
		(35 "F.Fab" user "Ref Des/Assembly Top")
		(33 "B.Fab" user "Ref Des/Assembly Bottom")
	)
	(footprint ""
		(layer "F.Cu")
		(at 178.619912 -350.098614 90)
		(property "Reference" "C387"
			(at 0 0 90)
			(layer "F.SilkS")
			(hide yes)
			(effects
				(font
					(size 1.27 1.27)
				)
			)
		)
		(property "Value" ""
			(at 0 0 90)
			(layer "F.Fab")
			(effects
				(font
					(size 1.27 1.27)
				)
			)
		)
		(duplicate_pad_numbers_are_jumpers no)
		(fp_line
			(start 0.299974 -0.150114)
			(end 0.299974 0.150114)
			(stroke
				(width 0.1)
				(type default)
			)
			(layer "F.Fab")
		)
		(fp_line
			(start -0.299974 -0.150114)
			(end 0.299974 -0.150114)
			(stroke
				(width 0.1)
				(type default)
			)
			(layer "F.Fab")
		)
		(fp_line
			(start 0.299974 0.150114)
			(end -0.299974 0.150114)
			(stroke
				(width 0.1)
				(type default)
			)
			(layer "F.Fab")
		)
		(fp_line
			(start -0.299974 0.150114)
			(end -0.299974 -0.150114)
			(stroke
				(width 0.1)
				(type default)
			)
			(layer "F.Fab")
		)
		(pad "1" smd rect
			(at -0.2667 0 90)
			(size 0.3048 0.381)
			(layers "F.Cu" "F.Mask" "F.Paste")
			(net "P5E_PEX1_STN7_TX_DN<120>")
		)
		(pad "2" smd rect
			(at 0.2667 0 90)
			(size 0.3048 0.381)
			(layers "F.Cu" "F.Mask" "F.Paste")
			(net "P5E_PEX1_STN7_TX_C_DN<120>")
		)
	)
	(footprint ""
		(layer "F.Cu")
		(at 213.6267 -55.418228 90)
		(property "Reference" "PC394"
			(at 0 0 90)
			(layer "F.SilkS")
			(hide yes)
			(effects
				(font
					(size 1.27 1.27)
				)
			)
		)
		(property "Value" ""
			(at 0 0 90)
			(layer "F.Fab")
			(effects
				(font
					(size 1.27 1.27)
				)
			)
		)
		(duplicate_pad_numbers_are_jumpers no)
		(fp_line
			(start 0.7874 -0.4064)
			(end 0.7874 0.4064)
			(stroke
				(width 0.1524)
				(type default)
			)
			(layer "F.SilkS")
		)
		(fp_line
			(start -0.7874 -0.4064)
			(end 0.7874 -0.4064)
			(stroke
				(width 0.1524)
				(type default)
			)
			(layer "F.SilkS")
		)
		(fp_line
			(start 0.7874 0.4064)
			(end -0.7874 0.4064)
			(stroke
				(width 0.1524)
				(type default)
			)
			(layer "F.SilkS")
		)
		(fp_line
			(start -0.7874 0.4064)
			(end -0.7874 -0.4064)
			(stroke
				(width 0.1524)
				(type default)
			)
			(layer "F.SilkS")
		)
		(fp_line
			(start -0.12065 -0.305054)
			(end -0.12065 -0.2794)
			(stroke
				(width 0.1)
				(type default)
			)
			(layer "F.Fab")
		)
		(fp_line
			(start -0.67945 -0.305054)
			(end -0.12065 -0.305054)
			(stroke
				(width 0.1)
				(type default)
			)
			(layer "F.Fab")
		)
		(fp_line
			(start 0.67945 -0.3048)
			(end 0.67945 0.3048)
			(stroke
				(width 0.1)
				(type default)
			)
			(layer "F.Fab")
		)
		(fp_line
			(start 0.12065 -0.3048)
			(end 0.67945 -0.3048)
			(stroke
				(width 0.1)
				(type default)
			)
			(layer "F.Fab")
		)
		(fp_line
			(start 0.12065 -0.2794)
			(end 0.12065 -0.3048)
			(stroke
				(width 0.1)
				(type default)
			)
			(layer "F.Fab")
		)
		(fp_line
			(start -0.12065 -0.2794)
			(end 0.12065 -0.2794)
			(stroke
				(width 0.1)
				(type default)
			)
			(layer "F.Fab")
		)
		(fp_line
			(start 0.120396 0.2794)
			(end -0.12065 0.2794)
			(stroke
				(width 0.1)
				(type default)
			)
			(layer "F.Fab")
		)
		(fp_line
			(start -0.12065 0.2794)
			(end -0.12065 0.3048)
			(stroke
				(width 0.1)
				(type default)
			)
			(layer "F.Fab")
		)
		(fp_line
			(start 0.67945 0.3048)
			(end 0.120396 0.3048)
			(stroke
				(width 0.1)
				(type default)
			)
			(layer "F.Fab")
		)
		(fp_line
			(start 0.120396 0.3048)
			(end 0.120396 0.2794)
			(stroke
				(width 0.1)
				(type default)
			)
			(layer "F.Fab")
		)
		(fp_line
			(start -0.12065 0.3048)
			(end -0.67945 0.3048)
			(stroke
				(width 0.1)
				(type default)
			)
			(layer "F.Fab")
		)
		(fp_line
			(start -0.67945 0.3048)
			(end -0.67945 -0.305054)
			(stroke
				(width 0.1)
				(type default)
			)
			(layer "F.Fab")
		)
		(pad "1" smd circle
			(at -0.40005 0 90)
			(size 0 0)
			(layers "F.Cu" "F.Mask" "F.Paste")
			(net "P12V_SSD7_R")
		)
		(pad "2" smd circle
			(at 0.40005 0 90)
			(size 0 0)
			(layers "F.Cu" "F.Mask" "F.Paste")
			(net "GND")
		)
	)
	(footprint ""
		(layer "F.Cu")
		(at 265.686286 -250.070874 -90)
		(property "Reference" "R1333"
			(at 0 0 270)
			(layer "F.SilkS")
			(hide yes)
			(effects
				(font
					(size 1.27 1.27)
				)
			)
		)
		(property "Value" ""
			(at 0 0 270)
			(layer "F.Fab")
			(effects
				(font
					(size 1.27 1.27)
				)
			)
		)
		(duplicate_pad_numbers_are_jumpers no)
		(fp_line
			(start -0.7874 0.4064)
			(end -0.7874 -0.4064)
			(stroke
				(width 0.1524)
				(type default)
			)
			(layer "F.SilkS")
		)
		(fp_line
			(start 0.7874 0.4064)
			(end -0.7874 0.4064)
			(stroke
				(width 0.1524)
				(type default)
			)
			(layer "F.SilkS")
		)
		(fp_line
			(start -0.7874 -0.4064)
			(end 0.7874 -0.4064)
			(stroke
				(width 0.1524)
				(type default)
			)
			(layer "F.SilkS")
		)
		(fp_line
			(start 0.7874 -0.4064)
			(end 0.7874 0.4064)
			(stroke
				(width 0.1524)
				(type default)
			)
			(layer "F.SilkS")
		)
		(fp_line
			(start -0.67945 0.3048)
			(end -0.67945 -0.305054)
			(stroke
				(width 0.1)
				(type default)
			)
			(layer "F.Fab")
		)
		(fp_line
			(start -0.12065 0.3048)
			(end -0.67945 0.3048)
			(stroke
				(width 0.1)
				(type default)
			)
			(layer "F.Fab")
		)
		(fp_line
			(start 0.120396 0.3048)
			(end 0.120396 0.2794)
			(stroke
				(width 0.1)
				(type default)
			)
			(layer "F.Fab")
		)
		(fp_line
			(start 0.67945 0.3048)
			(end 0.120396 0.3048)
			(stroke
				(width 0.1)
				(type default)
			)
			(layer "F.Fab")
		)
		(fp_line
			(start -0.12065 0.2794)
			(end -0.12065 0.3048)
			(stroke
				(width 0.1)
				(type default)
			)
			(layer "F.Fab")
		)
		(fp_line
			(start 0.120396 0.2794)
			(end -0.12065 0.2794)
			(stroke
				(width 0.1)
				(type default)
			)
			(layer "F.Fab")
		)
		(fp_line
			(start -0.12065 -0.2794)
			(end 0.12065 -0.2794)
			(stroke
				(width 0.1)
				(type default)
			)
			(layer "F.Fab")
		)
		(fp_line
			(start 0.12065 -0.2794)
			(end 0.12065 -0.3048)
			(stroke
				(width 0.1)
				(type default)
			)
			(layer "F.Fab")
		)
		(fp_line
			(start 0.12065 -0.3048)
			(end 0.67945 -0.3048)
			(stroke
				(width 0.1)
				(type default)
			)
			(layer "F.Fab")
		)
		(fp_line
			(start 0.67945 -0.3048)
			(end 0.67945 0.3048)
			(stroke
				(width 0.1)
				(type default)
			)
			(layer "F.Fab")
		)
		(fp_line
			(start -0.67945 -0.305054)
			(end -0.12065 -0.305054)
			(stroke
				(width 0.1)
				(type default)
			)
			(layer "F.Fab")
		)
		(fp_line
			(start -0.12065 -0.305054)
			(end -0.12065 -0.2794)
			(stroke
				(width 0.1)
				(type default)
			)
			(layer "F.Fab")
		)
		(pad "1" smd circle
			(at -0.40005 0 270)
			(size 0 0)
			(layers "F.Cu" "F.Mask" "F.Paste")
			(net "PEX2_DBG_MODE2")
		)
		(pad "2" smd circle
			(at 0.40005 0 270)
			(size 0 0)
			(layers "F.Cu" "F.Mask" "F.Paste")
			(net "P1V8_PEX")
		)
	)
	(footprint ""
		(layer "F.Cu")
		(at 32.71139 -27.04973 180)
		(property "Reference" "C2763"
			(at 0 0 180)
			(layer "F.SilkS")
			(hide yes)
			(effects
				(font
					(size 1.27 1.27)
				)
			)
		)
		(property "Value" ""
			(at 0 0 180)
			(layer "F.Fab")
			(effects
				(font
					(size 1.27 1.27)
				)
			)
		)
		(duplicate_pad_numbers_are_jumpers no)
		(fp_line
			(start 0.7874 0.4064)
			(end -0.7874 0.4064)
			(stroke
				(width 0.1524)
				(type default)
			)
			(layer "F.SilkS")
		)
		(fp_line
			(start 0.7874 -0.4064)
			(end 0.7874 0.4064)
			(stroke
				(width 0.1524)
				(type default)
			)
			(layer "F.SilkS")
		)
		(fp_line
			(start -0.7874 0.4064)
			(end -0.7874 -0.4064)
			(stroke
				(width 0.1524)
				(type default)
			)
			(layer "F.SilkS")
		)
		(fp_line
			(start -0.7874 -0.4064)
			(end 0.7874 -0.4064)
			(stroke
				(width 0.1524)
				(type default)
			)
			(layer "F.SilkS")
		)
		(fp_line
			(start 0.67945 0.3048)
			(end 0.120396 0.3048)
			(stroke
				(width 0.1)
				(type default)
			)
			(layer "F.Fab")
		)
		(fp_line
			(start 0.67945 -0.3048)
			(end 0.67945 0.3048)
			(stroke
				(width 0.1)
				(type default)
			)
			(layer "F.Fab")
		)
		(fp_line
			(start 0.12065 -0.2794)
			(end 0.12065 -0.3048)
			(stroke
				(width 0.1)
				(type default)
			)
			(layer "F.Fab")
		)
		(fp_line
			(start 0.12065 -0.3048)
			(end 0.67945 -0.3048)
			(stroke
				(width 0.1)
				(type default)
			)
			(layer "F.Fab")
		)
		(fp_line
			(start 0.120396 0.3048)
			(end 0.120396 0.2794)
			(stroke
				(width 0.1)
				(type default)
			)
			(layer "F.Fab")
		)
		(fp_line
			(start 0.120396 0.2794)
			(end -0.12065 0.2794)
			(stroke
				(width 0.1)
				(type default)
			)
			(layer "F.Fab")
		)
		(fp_line
			(start -0.12065 0.3048)
			(end -0.67945 0.3048)
			(stroke
				(width 0.1)
				(type default)
			)
			(layer "F.Fab")
		)
		(fp_line
			(start -0.12065 0.2794)
			(end -0.12065 0.3048)
			(stroke
				(width 0.1)
				(type default)
			)
			(layer "F.Fab")
		)
		(fp_line
			(start -0.12065 -0.2794)
			(end 0.12065 -0.2794)
			(stroke
				(width 0.1)
				(type default)
			)
			(layer "F.Fab")
		)
		(fp_line
			(start -0.12065 -0.305054)
			(end -0.12065 -0.2794)
			(stroke
				(width 0.1)
				(type default)
			)
			(layer "F.Fab")
		)
		(fp_line
			(start -0.67945 0.3048)
			(end -0.67945 -0.305054)
			(stroke
				(width 0.1)
				(type default)
			)
			(layer "F.Fab")
		)
		(fp_line
			(start -0.67945 -0.305054)
			(end -0.12065 -0.305054)
			(stroke
				(width 0.1)
				(type default)
			)
			(layer "F.Fab")
		)
		(pad "1" smd circle
			(at -0.40005 0 180)
			(size 0 0)
			(layers "F.Cu" "F.Mask" "F.Paste")
			(net "PRSNT_SSD1_R_N")
		)
		(pad "2" smd circle
			(at 0.40005 0 180)
			(size 0 0)
			(layers "F.Cu" "F.Mask" "F.Paste")
			(net "GND")
		)
	)
	(footprint ""
		(layer "F.Cu")
		(at 173.00194 -32.849312 90)
		(property "Reference" "R5678"
			(at 0 0 90)
			(layer "F.SilkS")
			(hide yes)
			(effects
				(font
					(size 1.27 1.27)
				)
			)
		)
		(property "Value" ""
			(at 0 0 90)
			(layer "F.Fab")
			(effects
				(font
					(size 1.27 1.27)
				)
			)
		)
		(duplicate_pad_numbers_are_jumpers no)
		(fp_line
			(start 0.7874 -0.4064)
			(end 0.7874 0.4064)
			(stroke
				(width 0.1524)
				(type default)
			)
			(layer "F.SilkS")
		)
		(fp_line
			(start -0.7874 -0.4064)
			(end 0.7874 -0.4064)
			(stroke
				(width 0.1524)
				(type default)
			)
			(layer "F.SilkS")
		)
		(fp_line
			(start 0.7874 0.4064)
			(end -0.7874 0.4064)
			(stroke
				(width 0.1524)
				(type default)
			)
			(layer "F.SilkS")
		)
		(fp_line
			(start -0.7874 0.4064)
			(end -0.7874 -0.4064)
			(stroke
				(width 0.1524)
				(type default)
			)
			(layer "F.SilkS")
		)
		(fp_line
			(start -0.12065 -0.305054)
			(end -0.12065 -0.2794)
			(stroke
				(width 0.1)
				(type default)
			)
			(layer "F.Fab")
		)
		(fp_line
			(start -0.67945 -0.305054)
			(end -0.12065 -0.305054)
			(stroke
				(width 0.1)
				(type default)
			)
			(layer "F.Fab")
		)
		(fp_line
			(start 0.67945 -0.3048)
			(end 0.67945 0.3048)
			(stroke
				(width 0.1)
				(type default)
			)
			(layer "F.Fab")
		)
		(fp_line
			(start 0.12065 -0.3048)
			(end 0.67945 -0.3048)
			(stroke
				(width 0.1)
				(type default)
			)
			(layer "F.Fab")
		)
		(fp_line
			(start 0.12065 -0.2794)
			(end 0.12065 -0.3048)
			(stroke
				(width 0.1)
				(type default)
			)
			(layer "F.Fab")
		)
		(fp_line
			(start -0.12065 -0.2794)
			(end 0.12065 -0.2794)
			(stroke
				(width 0.1)
				(type default)
			)
			(layer "F.Fab")
		)
		(fp_line
			(start 0.120396 0.2794)
			(end -0.12065 0.2794)
			(stroke
				(width 0.1)
				(type default)
			)
			(layer "F.Fab")
		)
		(fp_line
			(start -0.12065 0.2794)
			(end -0.12065 0.3048)
			(stroke
				(width 0.1)
				(type default)
			)
			(layer "F.Fab")
		)
		(fp_line
			(start 0.67945 0.3048)
			(end 0.120396 0.3048)
			(stroke
				(width 0.1)
				(type default)
			)
			(layer "F.Fab")
		)
		(fp_line
			(start 0.120396 0.3048)
			(end 0.120396 0.2794)
			(stroke
				(width 0.1)
				(type default)
			)
			(layer "F.Fab")
		)
		(fp_line
			(start -0.12065 0.3048)
			(end -0.67945 0.3048)
			(stroke
				(width 0.1)
				(type default)
			)
			(layer "F.Fab")
		)
		(fp_line
			(start -0.67945 0.3048)
			(end -0.67945 -0.305054)
			(stroke
				(width 0.1)
				(type default)
			)
			(layer "F.Fab")
		)
		(pad "1" smd circle
			(at -0.40005 0 90)
			(size 0 0)
			(layers "F.Cu" "F.Mask" "F.Paste")
			(net "RST_SMB_SSD6_ISO_R_N")
		)
		(pad "2" smd circle
			(at 0.40005 0 90)
			(size 0 0)
			(layers "F.Cu" "F.Mask" "F.Paste")
			(net "RST_SMB_SSD6_ISO_N")
		)
	)
	(footprint ""
		(layer "F.Cu")
		(at 430.961546 -132.601208 180)
		(property "Reference" "C654"
			(at 0 0 180)
			(layer "F.SilkS")
			(hide yes)
			(effects
				(font
					(size 1.27 1.27)
				)
			)
		)
		(property "Value" ""
			(at 0 0 180)
			(layer "F.Fab")
			(effects
				(font
					(size 1.27 1.27)
				)
			)
		)
		(duplicate_pad_numbers_are_jumpers no)
		(fp_line
			(start 0.299974 0.150114)
			(end -0.299974 0.150114)
			(stroke
				(width 0.1)
				(type default)
			)
			(layer "F.Fab")
		)
		(fp_line
			(start 0.299974 -0.150114)
			(end 0.299974 0.150114)
			(stroke
				(width 0.1)
				(type default)
			)
			(layer "F.Fab")
		)
		(fp_line
			(start -0.299974 0.150114)
			(end -0.299974 -0.150114)
			(stroke
				(width 0.1)
				(type default)
			)
			(layer "F.Fab")
		)
		(fp_line
			(start -0.299974 -0.150114)
			(end 0.299974 -0.150114)
			(stroke
				(width 0.1)
				(type default)
			)
			(layer "F.Fab")
		)
		(pad "1" smd rect
			(at -0.2667 0 180)
			(size 0.3048 0.381)
			(layers "F.Cu" "F.Mask" "F.Paste")
			(net "P5E_PEX3_STN0_TX_DP<5>")
		)
		(pad "2" smd rect
			(at 0.2667 0 180)
			(size 0.3048 0.381)
			(layers "F.Cu" "F.Mask" "F.Paste")
			(net "P5E_PEX3_STN0_TX_C_DP<5>")
		)
	)
	(footprint ""
		(layer "F.Cu")
		(at 375.252742 -262.649208 90)
		(property "Reference" "C3593"
			(at 0 0 90)
			(layer "F.SilkS")
			(hide yes)
			(effects
				(font
					(size 1.27 1.27)
				)
			)
		)
		(property "Value" ""
			(at 0 0 90)
			(layer "F.Fab")
			(effects
				(font
					(size 1.27 1.27)
				)
			)
		)
		(duplicate_pad_numbers_are_jumpers no)
		(fp_line
			(start 0.299974 -0.150114)
			(end 0.299974 0.150114)
			(stroke
				(width 0.1)
				(type default)
			)
			(layer "F.Fab")
		)
		(fp_line
			(start -0.299974 -0.150114)
			(end 0.299974 -0.150114)
			(stroke
				(width 0.1)
				(type default)
			)
			(layer "F.Fab")
		)
		(fp_line
			(start 0.299974 0.150114)
			(end -0.299974 0.150114)
			(stroke
				(width 0.1)
				(type default)
			)
			(layer "F.Fab")
		)
		(fp_line
			(start -0.299974 0.150114)
			(end -0.299974 -0.150114)
			(stroke
				(width 0.1)
				(type default)
			)
			(layer "F.Fab")
		)
		(pad "1" smd rect
			(at -0.2667 0 90)
			(size 0.3048 0.381)
			(layers "F.Cu" "F.Mask" "F.Paste")
			(net "P1V8_VDDA_PEX3")
		)
		(pad "2" smd rect
			(at 0.2667 0 90)
			(size 0.3048 0.381)
			(layers "F.Cu" "F.Mask" "F.Paste")
			(net "GND")
		)
	)
	(footprint ""
		(layer "F.Cu")
		(at 204.93609 -289.230816 90)
		(property "Reference" "R3940"
			(at 0 0 90)
			(layer "F.SilkS")
			(hide yes)
			(effects
				(font
					(size 1.27 1.27)
				)
			)
		)
		(property "Value" ""
			(at 0 0 90)
			(layer "F.Fab")
			(effects
				(font
					(size 1.27 1.27)
				)
			)
		)
		(duplicate_pad_numbers_are_jumpers no)
		(fp_line
			(start 0.7874 -0.4064)
			(end 0.7874 0.4064)
			(stroke
				(width 0.1524)
				(type default)
			)
			(layer "F.SilkS")
		)
		(fp_line
			(start -0.7874 -0.4064)
			(end 0.7874 -0.4064)
			(stroke
				(width 0.1524)
				(type default)
			)
			(layer "F.SilkS")
		)
		(fp_line
			(start 0.7874 0.4064)
			(end -0.7874 0.4064)
			(stroke
				(width 0.1524)
				(type default)
			)
			(layer "F.SilkS")
		)
		(fp_line
			(start -0.7874 0.4064)
			(end -0.7874 -0.4064)
			(stroke
				(width 0.1524)
				(type default)
			)
			(layer "F.SilkS")
		)
		(fp_line
			(start -0.12065 -0.305054)
			(end -0.12065 -0.2794)
			(stroke
				(width 0.1)
				(type default)
			)
			(layer "F.Fab")
		)
		(fp_line
			(start -0.67945 -0.305054)
			(end -0.12065 -0.305054)
			(stroke
				(width 0.1)
				(type default)
			)
			(layer "F.Fab")
		)
		(fp_line
			(start 0.67945 -0.3048)
			(end 0.67945 0.3048)
			(stroke
				(width 0.1)
				(type default)
			)
			(layer "F.Fab")
		)
		(fp_line
			(start 0.12065 -0.3048)
			(end 0.67945 -0.3048)
			(stroke
				(width 0.1)
				(type default)
			)
			(layer "F.Fab")
		)
		(fp_line
			(start 0.12065 -0.2794)
			(end 0.12065 -0.3048)
			(stroke
				(width 0.1)
				(type default)
			)
			(layer "F.Fab")
		)
		(fp_line
			(start -0.12065 -0.2794)
			(end 0.12065 -0.2794)
			(stroke
				(width 0.1)
				(type default)
			)
			(layer "F.Fab")
		)
		(fp_line
			(start 0.120396 0.2794)
			(end -0.12065 0.2794)
			(stroke
				(width 0.1)
				(type default)
			)
			(layer "F.Fab")
		)
		(fp_line
			(start -0.12065 0.2794)
			(end -0.12065 0.3048)
			(stroke
				(width 0.1)
				(type default)
			)
			(layer "F.Fab")
		)
		(fp_line
			(start 0.67945 0.3048)
			(end 0.120396 0.3048)
			(stroke
				(width 0.1)
				(type default)
			)
			(layer "F.Fab")
		)
		(fp_line
			(start 0.120396 0.3048)
			(end 0.120396 0.2794)
			(stroke
				(width 0.1)
				(type default)
			)
			(layer "F.Fab")
		)
		(fp_line
			(start -0.12065 0.3048)
			(end -0.67945 0.3048)
			(stroke
				(width 0.1)
				(type default)
			)
			(layer "F.Fab")
		)
		(fp_line
			(start -0.67945 0.3048)
			(end -0.67945 -0.305054)
			(stroke
				(width 0.1)
				(type default)
			)
			(layer "F.Fab")
		)
		(pad "1" smd circle
			(at -0.40005 0 90)
			(size 0 0)
			(layers "F.Cu" "F.Mask" "F.Paste")
			(net "SMB_PEX1_FPGA_SDA")
		)
		(pad "2" smd circle
			(at 0.40005 0 90)
			(size 0 0)
			(layers "F.Cu" "F.Mask" "F.Paste")
			(net "SMB_PEX1_HOST_LS_SDA")
		)
	)
)
